# SCM (Grand Teton) — schematic netlist excerpt (pin names and nets, part order shuffled) for the footprints in the layout excerpt that follows; sources: Cadence DE-HDL packaged netlist, KiCad conversion of 12092022_DA0F0TMDCD0_F0T_Management_Board_D_brd_V3_OCP.brd

X23  TP_TDR_4P_FTS  TP_TDR_4P_DIP EMPTY  pkg TH  page 60
  S1  = TDR_DIFF_100_IN4_DN
  P1  = GND_P1
  P2  = GND_P1
  S2  = TDR_DIFF_100_IN4_DP

R437  Q_RES  33.2 1% CHIP  pkg 0402LF  page 34 : A = SGPIO_PLD_DI_0 ; B = SGPIO_DI_0

(kicad_pcb
	(version 20260206)
	(generator "pcbnew")
	(generator_version "10.0")
	(general
		(thickness 1.6)
		(legacy_teardrops no)
	)
	(paper "A4")
	(title_block
		(title "12092022_DA0F0TMDCD0_F0T_Management_Board_D_brd_V3_OCP.brd")
		(comment 1 "Grand Teton / footprints 463-464 of 1440")
	)
	(layers
		(0 "F.Cu" signal "TOP")
		(4 "In1.Cu" signal "GND")
		(6 "In2.Cu" signal "IN1")
		(8 "In3.Cu" signal "GND1")
		(10 "In4.Cu" signal "IN2")
		(12 "In5.Cu" signal "VCC")
		(14 "In6.Cu" signal "VCC1")
		(16 "In7.Cu" signal "IN3")
		(18 "In8.Cu" signal "GND2")
		(20 "In9.Cu" signal "IN4")
		(22 "In10.Cu" signal "GND3")
		(2 "B.Cu" signal "BOTTOM")
		(9 "F.Adhes" user "F.Adhesive")
		(11 "B.Adhes" user "B.Adhesive")
		(13 "F.Paste" user "Package Geometry/Pastemask Top")
		(15 "B.Paste" user "Package Geometry/Pastemask Bottom")
		(5 "F.SilkS" user "Ref Des/Silkscreen Top")
		(7 "B.SilkS" user "Ref Des/Silkscreen Bottom")
		(1 "F.Mask" user "Board Geometry/Soldermask Top")
		(3 "B.Mask" user "Board Geometry/Soldermask Bottom")
		(17 "Dwgs.User" user "User.Drawings")
		(19 "Cmts.User" user "User.Comments")
		(21 "Eco1.User" user "User.Eco1")
		(23 "Eco2.User" user "User.Eco2")
		(25 "Edge.Cuts" user "Board Geometry/Outline")
		(27 "Margin" user)
		(31 "F.CrtYd" user "Package Geometry/Place Bound Top")
		(29 "B.CrtYd" user "Package Geometry/Place Bound Bottom")
		(35 "F.Fab" user "Ref Des/Assembly Top")
		(33 "B.Fab" user "Ref Des/Assembly Bottom")
	)
	(footprint ""
		(layer "F.Cu")
		(at 114.554 82.1436 -90)
		(property "Reference" "X23"
			(at -1.96723 3.1115 0)
			(unlocked yes)
			(layer "F.SilkS")
			(effects
				(font
					(size 0.7874 0.5842)
					(thickness 0.1524)
				)
				(justify left)
			)
		)
		(property "Value" ""
			(at 0 0 270)
			(layer "F.Fab")
			(effects
				(font
					(size 1.27 1.27)
				)
			)
		)
		(property "Device Type" "TP_TDR_4P_FTS_TH-TP_TDR_4P_DIPA"
			(at 1.30175 1.27 0)
			(unlocked yes)
			(layer "F.Fab")
			(hide yes)
			(effects
				(font
					(size 0.635 0.4064)
					(thickness 0.1524)
				)
			)
		)
		(property "User Part Number" "N_A"
			(at 1.30175 1.27 0)
			(unlocked yes)
			(layer "Cmts.User")
			(hide yes)
			(effects
				(font
					(size 0.635 0.4064)
					(thickness 0.1524)
				)
			)
		)
		(duplicate_pad_numbers_are_jumpers no)
		(fp_line
			(start 0 3.81)
			(end 2.54 3.81)
			(stroke
				(width 0.1524)
				(type default)
			)
			(layer "F.SilkS")
		)
		(fp_line
			(start 2.54 3.81)
			(end 2.54 3.6703)
			(stroke
				(width 0.1524)
				(type default)
			)
			(layer "F.SilkS")
		)
		(fp_line
			(start 0 3.175)
			(end 0 3.81)
			(stroke
				(width 0.1524)
				(type default)
			)
			(layer "F.SilkS")
		)
		(fp_line
			(start 2.54 1.4097)
			(end 2.54 1.1303)
			(stroke
				(width 0.1524)
				(type default)
			)
			(layer "F.SilkS")
		)
		(fp_line
			(start 0 0.635)
			(end 0 1.905)
			(stroke
				(width 0.1524)
				(type default)
			)
			(layer "F.SilkS")
		)
		(fp_line
			(start 2.54 -1.1303)
			(end 2.54 -1.27)
			(stroke
				(width 0.1524)
				(type default)
			)
			(layer "F.SilkS")
		)
		(fp_line
			(start 0 -1.27)
			(end 0 -0.635)
			(stroke
				(width 0.1524)
				(type default)
			)
			(layer "F.SilkS")
		)
		(fp_line
			(start 2.54 -1.27)
			(end 0 -1.27)
			(stroke
				(width 0.1524)
				(type default)
			)
			(layer "F.SilkS")
		)
		(fp_poly
			(pts
				(xy -0.761746 0) (xy -2.285746 -0.762) (xy -2.285746 0.762)
			)
			(stroke
				(width 0)
				(type default)
			)
			(fill yes)
			(layer "F.SilkS")
		)
		(fp_line
			(start 0 3.81)
			(end 2.54 3.81)
			(stroke
				(width 0.1)
				(type default)
			)
			(layer "F.Fab")
		)
		(fp_line
			(start 2.54 3.81)
			(end 2.54 -1.27)
			(stroke
				(width 0.1)
				(type default)
			)
			(layer "F.Fab")
		)
		(fp_line
			(start 0 -1.27)
			(end 0 3.81)
			(stroke
				(width 0.1)
				(type default)
			)
			(layer "F.Fab")
		)
		(fp_line
			(start 2.54 -1.27)
			(end 0 -1.27)
			(stroke
				(width 0.1)
				(type default)
			)
			(layer "F.Fab")
		)
		(fp_poly
			(pts
				(xy -0.761746 0) (xy -2.285746 -0.762) (xy -2.285746 0.762)
			)
			(stroke
				(width 0)
				(type default)
			)
			(fill yes)
			(layer "F.Fab")
		)
		(pad "1" thru_hole circle
			(at 0 0 270)
			(size 1.0033 1.0033)
			(drill 0.249936)
			(layers "*.Cu" "*.Mask")
			(remove_unused_layers no)
			(net "TDR_DIFF_100_IN4_DN")
			(clearance 0.10795)
			(thermal_gap 0.10795)
			(padstack
				(mode front_inner_back)
				(layer "Inner"
					(shape circle)
					(size 0.8001 0.8001)
					(clearance 0.1524)
				)
				(layer "B.Cu"
					(shape circle)
					(size 1.0033 1.0033)
					(clearance 0.10795)
				)
			)
		)
		(pad "2" thru_hole circle
			(at 2.54 0 270)
			(size 1.9939 1.9939)
			(drill 0.249936)
			(layers "*.Cu" "*.Mask")
			(remove_unused_layers no)
			(net "GND_P1")
			(clearance 0.10795)
			(thermal_gap 0.10795)
			(padstack
				(mode front_inner_back)
				(layer "Inner"
					(shape circle)
					(size 0.8001 0.8001)
					(clearance 0.1524)
				)
				(layer "B.Cu"
					(shape circle)
					(size 1.9939 1.9939)
					(clearance 0.10795)
				)
			)
		)
		(pad "3" thru_hole circle
			(at 2.54 2.54 270)
			(size 1.9939 1.9939)
			(drill 0.249936)
			(layers "*.Cu" "*.Mask")
			(remove_unused_layers no)
			(net "GND_P1")
			(clearance 0.10795)
			(thermal_gap 0.10795)
			(padstack
				(mode front_inner_back)
				(layer "Inner"
					(shape circle)
					(size 0.8001 0.8001)
					(clearance 0.1524)
				)
				(layer "B.Cu"
					(shape circle)
					(size 1.9939 1.9939)
					(clearance 0.10795)
				)
			)
		)
		(pad "4" thru_hole circle
			(at 0 2.54 270)
			(size 1.0033 1.0033)
			(drill 0.249936)
			(layers "*.Cu" "*.Mask")
			(remove_unused_layers no)
			(net "TDR_DIFF_100_IN4_DP")
			(clearance 0.10795)
			(thermal_gap 0.10795)
			(padstack
				(mode front_inner_back)
				(layer "Inner"
					(shape circle)
					(size 0.8001 0.8001)
					(clearance 0.1524)
				)
				(layer "B.Cu"
					(shape circle)
					(size 1.0033 1.0033)
					(clearance 0.10795)
				)
			)
		)
	)
	(footprint ""
		(layer "F.Cu")
		(at 12.319 -82.296 180)
		(property "Reference" "R437"
			(at 0 0 180)
			(layer "F.SilkS")
			(hide yes)
			(effects
				(font
					(size 1.27 1.27)
				)
			)
		)
		(property "Value" ""
			(at 0 0 180)
			(layer "F.Fab")
			(effects
				(font
					(size 1.27 1.27)
				)
			)
		)
		(duplicate_pad_numbers_are_jumpers no)
		(fp_line
			(start 0.7874 0.4064)
			(end -0.7874 0.4064)
			(stroke
				(width 0.1524)
				(type default)
			)
			(layer "F.SilkS")
		)
		(fp_line
			(start 0.7874 -0.4064)
			(end 0.7874 0.4064)
			(stroke
				(width 0.1524)
				(type default)
			)
			(layer "F.SilkS")
		)
		(fp_line
			(start -0.7874 0.4064)
			(end -0.7874 -0.4064)
			(stroke
				(width 0.1524)
				(type default)
			)
			(layer "F.SilkS")
		)
		(fp_line
			(start -0.7874 -0.4064)
			(end 0.7874 -0.4064)
			(stroke
				(width 0.1524)
				(type default)
			)
			(layer "F.SilkS")
		)
		(fp_line
			(start 0.67945 0.3048)
			(end 0.120396 0.3048)
			(stroke
				(width 0.1)
				(type default)
			)
			(layer "F.Fab")
		)
		(fp_line
			(start 0.67945 -0.3048)
			(end 0.67945 0.3048)
			(stroke
				(width 0.1)
				(type default)
			)
			(layer "F.Fab")
		)
		(fp_line
			(start 0.12065 -0.2794)
			(end 0.12065 -0.3048)
			(stroke
				(width 0.1)
				(type default)
			)
			(layer "F.Fab")
		)
		(fp_line
			(start 0.12065 -0.3048)
			(end 0.67945 -0.3048)
			(stroke
				(width 0.1)
				(type default)
			)
			(layer "F.Fab")
		)
		(fp_line
			(start 0.120396 0.3048)
			(end 0.120396 0.2794)
			(stroke
				(width 0.1)
				(type default)
			)
			(layer "F.Fab")
		)
		(fp_line
			(start 0.120396 0.2794)
			(end -0.12065 0.2794)
			(stroke
				(width 0.1)
				(type default)
			)
			(layer "F.Fab")
		)
		(fp_line
			(start -0.12065 0.3048)
			(end -0.67945 0.3048)
			(stroke
				(width 0.1)
				(type default)
			)
			(layer "F.Fab")
		)
		(fp_line
			(start -0.12065 0.2794)
			(end -0.12065 0.3048)
			(stroke
				(width 0.1)
				(type default)
			)
			(layer "F.Fab")
		)
		(fp_line
			(start -0.12065 -0.2794)
			(end 0.12065 -0.2794)
			(stroke
				(width 0.1)
				(type default)
			)
			(layer "F.Fab")
		)
		(fp_line
			(start -0.12065 -0.305054)
			(end -0.12065 -0.2794)
			(stroke
				(width 0.1)
				(type default)
			)
			(layer "F.Fab")
		)
		(fp_line
			(start -0.67945 0.3048)
			(end -0.67945 -0.305054)
			(stroke
				(width 0.1)
				(type default)
			)
			(layer "F.Fab")
		)
		(fp_line
			(start -0.67945 -0.305054)
			(end -0.12065 -0.305054)
			(stroke
				(width 0.1)
				(type default)
			)
			(layer "F.Fab")
		)
		(pad "1" smd circle
			(at -0.40005 0 180)
			(size 0 0)
			(layers "F.Cu" "F.Mask" "F.Paste")
			(net "SGPIO_PLD_DI_0")
		)
		(pad "2" smd circle
			(at 0.40005 0 180)
			(size 0 0)
			(layers "F.Cu" "F.Mask" "F.Paste")
			(net "SGPIO_DI_0")
		)
	)
)
